# S9S_MB_2U (Grand Teton) — schematic netlist excerpt (pin names and nets, part order shuffled) for the footprints in the layout excerpt that follows; sources: Cadence DE-HDL packaged netlist, KiCad conversion of 03242023_DA0F0TMBIJ0_F0T_Motherboard_J_brd_V01_OCP.brd

R15  Q_RES  0 5% CHIP  pkg 0402LF  page 14 : A = SVID_DIO1_CPU0 ; B = SVID_DIO1_CPU0_R
C519  Q_CAP  47UF 2.5V 20% X6S  pkg C0603  page 76 : A = PVCCFA_EHV_CPU0 ; B = GND

(kicad_pcb
	(version 20260206)
	(generator "pcbnew")
	(generator_version "10.0")
	(general
		(thickness 1.6)
		(legacy_teardrops no)
	)
	(paper "A4")
	(title_block
		(title "03242023_DA0F0TMBIJ0_F0T_Motherboard_J_brd_V01_OCP.brd")
		(comment 1 "Grand Teton / footprints 5678-5679 of 6105")
	)
	(layers
		(0 "F.Cu" signal "TOP")
		(4 "In1.Cu" signal "GND")
		(6 "In2.Cu" signal "IN1")
		(8 "In3.Cu" signal "GND1")
		(10 "In4.Cu" signal "IN2")
		(12 "In5.Cu" signal "GND2")
		(14 "In6.Cu" signal "IN3")
		(16 "In7.Cu" signal "GND3")
		(18 "In8.Cu" signal "VCC")
		(20 "In9.Cu" signal "VCC1")
		(22 "In10.Cu" signal "GND4")
		(24 "In11.Cu" signal "IN4")
		(26 "In12.Cu" signal "GND5")
		(28 "In13.Cu" signal "IN5")
		(30 "In14.Cu" signal "GND6")
		(32 "In15.Cu" signal "IN6")
		(34 "In16.Cu" signal "GND7")
		(2 "B.Cu" signal "BOTTOM")
		(9 "F.Adhes" user "F.Adhesive")
		(11 "B.Adhes" user "B.Adhesive")
		(13 "F.Paste" user "Package Geometry/Pastemask Top")
		(15 "B.Paste" user "Package Geometry/Pastemask Bottom")
		(5 "F.SilkS" user "Ref Des/Silkscreen Top")
		(7 "B.SilkS" user "Ref Des/Silkscreen Bottom")
		(1 "F.Mask" user "Board Geometry/Soldermask Top")
		(3 "B.Mask" user "Board Geometry/Soldermask Bottom")
		(17 "Dwgs.User" user "User.Drawings")
		(19 "Cmts.User" user "User.Comments")
		(21 "Eco1.User" user "User.Eco1")
		(23 "Eco2.User" user "User.Eco2")
		(25 "Edge.Cuts" user "Board Geometry/Outline")
		(27 "Margin" user)
		(31 "F.CrtYd" user "Package Geometry/Place Bound Top")
		(29 "B.CrtYd" user "Package Geometry/Place Bound Bottom")
		(35 "F.Fab" user "Ref Des/Assembly Top")
		(33 "B.Fab" user "Ref Des/Assembly Bottom")
	)
	(footprint ""
		(layer "B.Cu")
		(at 307.069998 -192.60947 90)
		(property "Reference" "R15"
			(at 0 0 90)
			(layer "B.SilkS")
			(hide yes)
			(effects
				(font
					(size 1.27 1.27)
				)
				(justify mirror)
			)
		)
		(property "Value" ""
			(at 0 0 90)
			(layer "B.Fab")
			(effects
				(font
					(size 1.27 1.27)
				)
				(justify mirror)
			)
		)
		(duplicate_pad_numbers_are_jumpers no)
		(fp_line
			(start 0.7874 -0.4064)
			(end -0.7874 -0.4064)
			(stroke
				(width 0.1524)
				(type default)
			)
			(layer "B.SilkS")
		)
		(fp_line
			(start -0.7874 -0.4064)
			(end -0.7874 0.4064)
			(stroke
				(width 0.1524)
				(type default)
			)
			(layer "B.SilkS")
		)
		(fp_line
			(start 0.7874 0.4064)
			(end 0.7874 -0.4064)
			(stroke
				(width 0.1524)
				(type default)
			)
			(layer "B.SilkS")
		)
		(fp_line
			(start -0.7874 0.4064)
			(end 0.7874 0.4064)
			(stroke
				(width 0.1524)
				(type default)
			)
			(layer "B.SilkS")
		)
		(fp_line
			(start 0.67945 -0.305054)
			(end 0.12065 -0.305054)
			(stroke
				(width 0.1)
				(type default)
			)
			(layer "B.Fab")
		)
		(fp_line
			(start 0.12065 -0.305054)
			(end 0.12065 -0.2794)
			(stroke
				(width 0.1)
				(type default)
			)
			(layer "B.Fab")
		)
		(fp_line
			(start -0.12065 -0.3048)
			(end -0.67945 -0.3048)
			(stroke
				(width 0.1)
				(type default)
			)
			(layer "B.Fab")
		)
		(fp_line
			(start -0.67945 -0.3048)
			(end -0.67945 0.3048)
			(stroke
				(width 0.1)
				(type default)
			)
			(layer "B.Fab")
		)
		(fp_line
			(start 0.12065 -0.2794)
			(end -0.12065 -0.2794)
			(stroke
				(width 0.1)
				(type default)
			)
			(layer "B.Fab")
		)
		(fp_line
			(start -0.12065 -0.2794)
			(end -0.12065 -0.3048)
			(stroke
				(width 0.1)
				(type default)
			)
			(layer "B.Fab")
		)
		(fp_line
			(start 0.12065 0.2794)
			(end 0.12065 0.3048)
			(stroke
				(width 0.1)
				(type default)
			)
			(layer "B.Fab")
		)
		(fp_line
			(start -0.120396 0.2794)
			(end 0.12065 0.2794)
			(stroke
				(width 0.1)
				(type default)
			)
			(layer "B.Fab")
		)
		(fp_line
			(start 0.67945 0.3048)
			(end 0.67945 -0.305054)
			(stroke
				(width 0.1)
				(type default)
			)
			(layer "B.Fab")
		)
		(fp_line
			(start 0.12065 0.3048)
			(end 0.67945 0.3048)
			(stroke
				(width 0.1)
				(type default)
			)
			(layer "B.Fab")
		)
		(fp_line
			(start -0.120396 0.3048)
			(end -0.120396 0.2794)
			(stroke
				(width 0.1)
				(type default)
			)
			(layer "B.Fab")
		)
		(fp_line
			(start -0.67945 0.3048)
			(end -0.120396 0.3048)
			(stroke
				(width 0.1)
				(type default)
			)
			(layer "B.Fab")
		)
		(pad "1" smd circle
			(at 0.40005 0 270)
			(size 0 0)
			(layers "B.Cu" "B.Mask" "B.Paste")
			(net "SVID_DIO1_CPU0")
		)
		(pad "2" smd circle
			(at -0.40005 0 270)
			(size 0 0)
			(layers "B.Cu" "B.Mask" "B.Paste")
			(net "SVID_DIO1_CPU0_R")
		)
	)
	(footprint ""
		(layer "B.Cu")
		(at 349.344742 -212.049614 180)
		(property "Reference" "C519"
			(at 0 0 0)
			(layer "B.SilkS")
			(hide yes)
			(effects
				(font
					(size 1.27 1.27)
				)
				(justify mirror)
			)
		)
		(property "Value" ""
			(at 0 0 0)
			(layer "B.Fab")
			(effects
				(font
					(size 1.27 1.27)
				)
				(justify mirror)
			)
		)
		(duplicate_pad_numbers_are_jumpers no)
		(fp_line
			(start 1.2954 0.5842)
			(end 1.2954 -0.5842)
			(stroke
				(width 0.1524)
				(type default)
			)
			(layer "B.SilkS")
		)
		(fp_line
			(start 1.2954 -0.5842)
			(end -1.2954 -0.5842)
			(stroke
				(width 0.1524)
				(type default)
			)
			(layer "B.SilkS")
		)
		(fp_line
			(start 0 -0.5842)
			(end 0 0.5842)
			(stroke
				(width 0.1524)
				(type default)
			)
			(layer "B.SilkS")
		)
		(fp_line
			(start -1.2954 0.5842)
			(end 1.2954 0.5842)
			(stroke
				(width 0.1524)
				(type default)
			)
			(layer "B.SilkS")
		)
		(fp_line
			(start -1.2954 -0.5842)
			(end -1.2954 0.5842)
			(stroke
				(width 0.1524)
				(type default)
			)
			(layer "B.SilkS")
		)
		(fp_line
			(start 1.1938 0.4064)
			(end 1.1938 -0.4064)
			(stroke
				(width 0.1)
				(type default)
			)
			(layer "B.Fab")
		)
		(fp_line
			(start 1.1938 -0.4064)
			(end 0.8636 -0.4064)
			(stroke
				(width 0.1)
				(type default)
			)
			(layer "B.Fab")
		)
		(fp_line
			(start 0.8636 0.4572)
			(end 0.8636 0.4064)
			(stroke
				(width 0.1)
				(type default)
			)
			(layer "B.Fab")
		)
		(fp_line
			(start 0.8636 0.4064)
			(end 1.1938 0.4064)
			(stroke
				(width 0.1)
				(type default)
			)
			(layer "B.Fab")
		)
		(fp_line
			(start 0.8636 -0.4064)
			(end 0.8636 -0.4572)
			(stroke
				(width 0.1)
				(type default)
			)
			(layer "B.Fab")
		)
		(fp_line
			(start 0.8636 -0.4572)
			(end -0.8636 -0.4572)
			(stroke
				(width 0.1)
				(type default)
			)
			(layer "B.Fab")
		)
		(fp_line
			(start -0.8636 0.4572)
			(end 0.8636 0.4572)
			(stroke
				(width 0.1)
				(type default)
			)
			(layer "B.Fab")
		)
		(fp_line
			(start -0.8636 0.4064)
			(end -0.8636 0.4572)
			(stroke
				(width 0.1)
				(type default)
			)
			(layer "B.Fab")
		)
		(fp_line
			(start -0.8636 -0.4064)
			(end -1.1938 -0.4064)
			(stroke
				(width 0.1)
				(type default)
			)
			(layer "B.Fab")
		)
		(fp_line
			(start -0.8636 -0.4572)
			(end -0.8636 -0.4064)
			(stroke
				(width 0.1)
				(type default)
			)
			(layer "B.Fab")
		)
		(fp_line
			(start -1.1938 0.4064)
			(end -0.8636 0.4064)
			(stroke
				(width 0.1)
				(type default)
			)
			(layer "B.Fab")
		)
		(fp_line
			(start -1.1938 -0.4064)
			(end -1.1938 0.4064)
			(stroke
				(width 0.1)
				(type default)
			)
			(layer "B.Fab")
		)
		(pad "1" smd rect
			(at 0.7366 0 90)
			(size 0.7112 0.8128)
			(layers "B.Cu" "B.Mask" "B.Paste")
			(net "PVCCFA_EHV_CPU0")
		)
		(pad "2" smd rect
			(at -0.7366 0 90)
			(size 0.7112 0.8128)
			(layers "B.Cu" "B.Mask" "B.Paste")
			(net "GND")
		)
	)
)
